#ISCELL
  pure_quanta quanta_title_block_c *
  *
#ISCELL
  standard offpage *
  page305_i1
#CELL
  pure_quanta q_led *
  page305_i10
#ISCELL
  logical_power universal_gnd *
  page305_i11
#ISCELL
  logical_power universal_gnd *
  page305_i12
#CELL
  pure_quanta q_led *
  page305_i13
#ISCELL
  logical_power universal_power *
  page305_i17
#ISCELL
  standard offpage *
  page305_i18
#ISCELL
  logical_power universal_power *
  page305_i19
#CELL
  pure_quanta mosfet_nch_dual *
  page305_i2
#ISCELL
  logical_power universal_gnd *
  page305_i20
#CELL
  pure_quanta q_led *
  page305_i21
#CELL
  pure_quanta q_led *
  page305_i22
#ISCELL
  logical_power universal_power *
  page305_i25
#ISCELL
  standard offpage *
  page305_i26
#ISCELL
  logical_power universal_power *
  page305_i27
#ISCELL
  standard offpage *
  page305_i28
#ISCELL
  standard offpage *
  page305_i3
#CELL
  pure_quanta mosfet_nch_dual *
  page305_i32
#ISCELL
  logical_power universal_gnd *
  page305_i33
#ISCELL
  logical_power universal_gnd *
  page305_i34
#CELL
  pure_quanta q_led *
  page305_i35
#ISCELL
  logical_power universal_power *
  page305_i39
#CELL
  pure_quanta mosfet_nch_dual *
  page305_i4
#CELL
  pure_quanta mosfet_nch_dual *
  page305_i40
#CELL
  pure_quanta mosfet_nch_dual *
  page305_i41
#ISCELL
  logical_power universal_gnd *
  page305_i42
#CELL
  pure_quanta q_led *
  page305_i43
#CELL
  pure_quanta q_led *
  page305_i44
#ISCELL
  logical_power universal_power *
  page305_i46
#ISCELL
  logical_power universal_power *
  page305_i48
#CELL
  pure_quanta q_res *
  page305_i49
#ISCELL
  standard offpage *
  page305_i5
#CELL
  pure_quanta q_res *
  page305_i50
#CELL
  pure_quanta q_res *
  page305_i51
#CELL
  pure_quanta q_res *
  page305_i52
#CELL
  pure_quanta q_res *
  page305_i53
#CELL
  pure_quanta q_res *
  page305_i54
#CELL
  pure_quanta q_res *
  page305_i55
#ISCELL
  standard offpage *
  page305_i6
#CELL
  pure_quanta mosfet_nch_dual *
  page305_i7
#CELL
  pure_quanta mosfet_nch_dual *
  page305_i8
#ISCELL
  logical_power universal_gnd *
  page305_i9
